# T6G (Grand Teton) — schematic netlist excerpt (pin names and nets, part order shuffled) for the footprints in the layout excerpt that follows; sources: Cadence DE-HDL packaged netlist, KiCad conversion of 04192023_DAF0TMB3IC0_F0TG_MB_C_brd_V02_OCP.brd

R3671  Q_RES  0 5% CHIP  pkg 0402LF  page 257 : A = SMB_SCM_2_R4_SDA ; B = SMB_SEN_TIC_3V3AUX_SDA
PR3949  Q_RES  56K 1% CHIP  pkg 0402LF  page 147 : A = P12V_E1S_IMON_0 ; B = GND

(kicad_pcb
	(version 20260206)
	(generator "pcbnew")
	(generator_version "10.0")
	(general
		(thickness 1.6)
		(legacy_teardrops no)
	)
	(paper "A4")
	(title_block
		(title "04192023_DAF0TMB3IC0_F0TG_MB_C_brd_V02_OCP.brd")
		(comment 1 "Grand Teton / footprints 2120-2121 of 8354")
	)
	(layers
		(0 "F.Cu" signal "TOP")
		(4 "In1.Cu" signal "GND")
		(6 "In2.Cu" signal "IN1")
		(8 "In3.Cu" signal "GND1")
		(10 "In4.Cu" signal "IN2")
		(12 "In5.Cu" signal "GND2")
		(14 "In6.Cu" signal "IN3")
		(16 "In7.Cu" signal "GND3")
		(18 "In8.Cu" signal "VCC")
		(20 "In9.Cu" signal "VCC1")
		(22 "In10.Cu" signal "GND4")
		(24 "In11.Cu" signal "IN4")
		(26 "In12.Cu" signal "GND5")
		(28 "In13.Cu" signal "IN5")
		(30 "In14.Cu" signal "GND6")
		(32 "In15.Cu" signal "IN6")
		(34 "In16.Cu" signal "GND7")
		(2 "B.Cu" signal "BOTTOM")
		(9 "F.Adhes" user "F.Adhesive")
		(11 "B.Adhes" user "B.Adhesive")
		(13 "F.Paste" user "Package Geometry/Pastemask Top")
		(15 "B.Paste" user "Package Geometry/Pastemask Bottom")
		(5 "F.SilkS" user "Ref Des/Silkscreen Top")
		(7 "B.SilkS" user "Ref Des/Silkscreen Bottom")
		(1 "F.Mask" user "Board Geometry/Soldermask Top")
		(3 "B.Mask" user "Board Geometry/Soldermask Bottom")
		(17 "Dwgs.User" user "User.Drawings")
		(19 "Cmts.User" user "User.Comments")
		(21 "Eco1.User" user "User.Eco1")
		(23 "Eco2.User" user "User.Eco2")
		(25 "Edge.Cuts" user "Board Geometry/Outline")
		(27 "Margin" user)
		(31 "F.CrtYd" user "Package Geometry/Place Bound Top")
		(29 "B.CrtYd" user "Package Geometry/Place Bound Bottom")
		(35 "F.Fab" user "Ref Des/Assembly Top")
		(33 "B.Fab" user "Ref Des/Assembly Bottom")
	)
	(footprint ""
		(layer "F.Cu")
		(at 305.819048 -46.021498)
		(property "Reference" "R3671"
			(at 0 0 0)
			(layer "F.SilkS")
			(hide yes)
			(effects
				(font
					(size 1.27 1.27)
				)
			)
		)
		(property "Value" ""
			(at 0 0 0)
			(layer "F.Fab")
			(effects
				(font
					(size 1.27 1.27)
				)
			)
		)
		(duplicate_pad_numbers_are_jumpers no)
		(fp_line
			(start -0.7874 -0.4064)
			(end 0.7874 -0.4064)
			(stroke
				(width 0.1524)
				(type default)
			)
			(layer "F.SilkS")
		)
		(fp_line
			(start -0.7874 0.4064)
			(end -0.7874 -0.4064)
			(stroke
				(width 0.1524)
				(type default)
			)
			(layer "F.SilkS")
		)
		(fp_line
			(start 0.7874 -0.4064)
			(end 0.7874 0.4064)
			(stroke
				(width 0.1524)
				(type default)
			)
			(layer "F.SilkS")
		)
		(fp_line
			(start 0.7874 0.4064)
			(end -0.7874 0.4064)
			(stroke
				(width 0.1524)
				(type default)
			)
			(layer "F.SilkS")
		)
		(fp_line
			(start -0.67945 -0.305054)
			(end -0.12065 -0.305054)
			(stroke
				(width 0.1)
				(type default)
			)
			(layer "F.Fab")
		)
		(fp_line
			(start -0.67945 0.3048)
			(end -0.67945 -0.305054)
			(stroke
				(width 0.1)
				(type default)
			)
			(layer "F.Fab")
		)
		(fp_line
			(start -0.12065 -0.305054)
			(end -0.12065 -0.2794)
			(stroke
				(width 0.1)
				(type default)
			)
			(layer "F.Fab")
		)
		(fp_line
			(start -0.12065 -0.2794)
			(end 0.12065 -0.2794)
			(stroke
				(width 0.1)
				(type default)
			)
			(layer "F.Fab")
		)
		(fp_line
			(start -0.12065 0.2794)
			(end -0.12065 0.3048)
			(stroke
				(width 0.1)
				(type default)
			)
			(layer "F.Fab")
		)
		(fp_line
			(start -0.12065 0.3048)
			(end -0.67945 0.3048)
			(stroke
				(width 0.1)
				(type default)
			)
			(layer "F.Fab")
		)
		(fp_line
			(start 0.120396 0.2794)
			(end -0.12065 0.2794)
			(stroke
				(width 0.1)
				(type default)
			)
			(layer "F.Fab")
		)
		(fp_line
			(start 0.120396 0.3048)
			(end 0.120396 0.2794)
			(stroke
				(width 0.1)
				(type default)
			)
			(layer "F.Fab")
		)
		(fp_line
			(start 0.12065 -0.3048)
			(end 0.67945 -0.3048)
			(stroke
				(width 0.1)
				(type default)
			)
			(layer "F.Fab")
		)
		(fp_line
			(start 0.12065 -0.2794)
			(end 0.12065 -0.3048)
			(stroke
				(width 0.1)
				(type default)
			)
			(layer "F.Fab")
		)
		(fp_line
			(start 0.67945 -0.3048)
			(end 0.67945 0.3048)
			(stroke
				(width 0.1)
				(type default)
			)
			(layer "F.Fab")
		)
		(fp_line
			(start 0.67945 0.3048)
			(end 0.120396 0.3048)
			(stroke
				(width 0.1)
				(type default)
			)
			(layer "F.Fab")
		)
		(pad "1" smd circle
			(at -0.40005 0)
			(size 0 0)
			(layers "F.Cu" "F.Mask" "F.Paste")
			(net "SMB_SCM_2_R4_SDA")
		)
		(pad "2" smd circle
			(at 0.40005 0)
			(size 0 0)
			(layers "F.Cu" "F.Mask" "F.Paste")
			(net "SMB_SEN_TIC_3V3AUX_SDA")
		)
	)
	(footprint ""
		(layer "F.Cu")
		(at 257.85953 -55.479442)
		(property "Reference" "PR3949"
			(at 0 0 0)
			(layer "F.SilkS")
			(hide yes)
			(effects
				(font
					(size 1.27 1.27)
				)
			)
		)
		(property "Value" ""
			(at 0 0 0)
			(layer "F.Fab")
			(effects
				(font
					(size 1.27 1.27)
				)
			)
		)
		(duplicate_pad_numbers_are_jumpers no)
		(fp_line
			(start -0.7874 -0.4064)
			(end 0.7874 -0.4064)
			(stroke
				(width 0.1524)
				(type default)
			)
			(layer "F.SilkS")
		)
		(fp_line
			(start -0.7874 0.4064)
			(end -0.7874 -0.4064)
			(stroke
				(width 0.1524)
				(type default)
			)
			(layer "F.SilkS")
		)
		(fp_line
			(start 0.7874 -0.4064)
			(end 0.7874 0.4064)
			(stroke
				(width 0.1524)
				(type default)
			)
			(layer "F.SilkS")
		)
		(fp_line
			(start 0.7874 0.4064)
			(end -0.7874 0.4064)
			(stroke
				(width 0.1524)
				(type default)
			)
			(layer "F.SilkS")
		)
		(fp_line
			(start -0.67945 -0.305054)
			(end -0.12065 -0.305054)
			(stroke
				(width 0.1)
				(type default)
			)
			(layer "F.Fab")
		)
		(fp_line
			(start -0.67945 0.3048)
			(end -0.67945 -0.305054)
			(stroke
				(width 0.1)
				(type default)
			)
			(layer "F.Fab")
		)
		(fp_line
			(start -0.12065 -0.305054)
			(end -0.12065 -0.2794)
			(stroke
				(width 0.1)
				(type default)
			)
			(layer "F.Fab")
		)
		(fp_line
			(start -0.12065 -0.2794)
			(end 0.12065 -0.2794)
			(stroke
				(width 0.1)
				(type default)
			)
			(layer "F.Fab")
		)
		(fp_line
			(start -0.12065 0.2794)
			(end -0.12065 0.3048)
			(stroke
				(width 0.1)
				(type default)
			)
			(layer "F.Fab")
		)
		(fp_line
			(start -0.12065 0.3048)
			(end -0.67945 0.3048)
			(stroke
				(width 0.1)
				(type default)
			)
			(layer "F.Fab")
		)
		(fp_line
			(start 0.120396 0.2794)
			(end -0.12065 0.2794)
			(stroke
				(width 0.1)
				(type default)
			)
			(layer "F.Fab")
		)
		(fp_line
			(start 0.120396 0.3048)
			(end 0.120396 0.2794)
			(stroke
				(width 0.1)
				(type default)
			)
			(layer "F.Fab")
		)
		(fp_line
			(start 0.12065 -0.3048)
			(end 0.67945 -0.3048)
			(stroke
				(width 0.1)
				(type default)
			)
			(layer "F.Fab")
		)
		(fp_line
			(start 0.12065 -0.2794)
			(end 0.12065 -0.3048)
			(stroke
				(width 0.1)
				(type default)
			)
			(layer "F.Fab")
		)
		(fp_line
			(start 0.67945 -0.3048)
			(end 0.67945 0.3048)
			(stroke
				(width 0.1)
				(type default)
			)
			(layer "F.Fab")
		)
		(fp_line
			(start 0.67945 0.3048)
			(end 0.120396 0.3048)
			(stroke
				(width 0.1)
				(type default)
			)
			(layer "F.Fab")
		)
		(pad "1" smd circle
			(at -0.40005 0)
			(size 0 0)
			(layers "F.Cu" "F.Mask" "F.Paste")
			(net "P12V_E1S_IMON_0")
		)
		(pad "2" smd circle
			(at 0.40005 0)
			(size 0 0)
			(layers "F.Cu" "F.Mask" "F.Paste")
			(net "GND")
		)
	)
)
